#ISCELL
  mstr_misc dns *
  *
#ISCELL
  pure_quanta quanta_title_block_c *
  *
#CELL
  pure_quanta q_res *
  page160_i123
#CELL
  pure_quanta q_res *
  page160_i124
#ISCELL
  logical_power universal_power *
  page160_i125
#ISCELL
  logical_power universal_gnd *
  page160_i126
#CELL
  pure_quanta q_res *
  page160_i127
#ISCELL
  logical_power universal_gnd *
  page160_i137
#ISCELL
  logical_power universal_gnd *
  page160_i138
#CELL
  pure_quanta q_res *
  page160_i139
#ISCELL
  standard offpage *
  page160_i146
#CELL
  pure_quanta q_cap *
  page160_i148
#ISCELL
  logical_power universal_gnd *
  page160_i149
#CELL
  pure_quanta 74lvc2g17gw *
  page160_i153
#ISCELL
  logical_power universal_power *
  page160_i154
#ISCELL
  logical_power universal_gnd *
  page160_i16
#ISCELL
  standard offpage *
  page160_i161
#ISCELL
  logical_power universal_power *
  page160_i163
#CELL
  pure_quanta q_res *
  page160_i164
#CELL
  pure_quanta q_res *
  page160_i165
#ISCELL
  logical_power universal_gnd *
  page160_i166
#ISCELL
  logical_power universal_power *
  page160_i167
#CELL
  pure_quanta q_res *
  page160_i168
#ISCELL
  standard offpage *
  page160_i169
#CELL
  pure_quanta q_res *
  page160_i170
#ISCELL
  logical_power universal_gnd *
  page160_i171
#ISCELL
  standard offpage *
  page160_i172
#CELL
  pure_quanta 74lvc2g17gw *
  page160_i173
#ISCELL
  logical_power universal_power *
  page160_i174
#CELL
  pure_quanta q_cap *
  page160_i175
#ISCELL
  logical_power universal_gnd *
  page160_i176
#ISCELL
  logical_power universal_gnd *
  page160_i177
#ISCELL
  logical_power universal_gnd *
  page160_i178
#ISCELL
  standard offpage *
  page160_i179
#ISCELL
  standard offpage *
  page160_i18
#CELL
  pure_quanta q_res *
  page160_i181
#ISCELL
  standard offpage *
  page160_i182
#CELL
  pure_quanta q_res *
  page160_i184
#ISCELL
  logical_power universal_gnd *
  page160_i185
#ISCELL
  logical_power universal_power *
  page160_i186
#CELL
  pure_quanta q_res *
  page160_i187
#CELL
  pure_quanta q_res *
  page160_i188
#ISCELL
  logical_power universal_gnd *
  page160_i189
#ISCELL
  standard offpage *
  page160_i190
#ISCELL
  logical_power universal_power *
  page160_i191
#CELL
  pure_quanta q_res *
  page160_i192
#ISCELL
  standard offpage *
  page160_i194
#CELL
  pure_quanta q_res *
  page160_i195
#ISCELL
  logical_power universal_gnd *
  page160_i196
#CELL
  pure_quanta q_res *
  page160_i197
#CELL
  pure_quanta q_res *
  page160_i198
#CELL
  pure_quanta q_res *
  page160_i199
#ISCELL
  logical_power universal_power *
  page160_i20
#CELL
  pure_quanta q_res *
  page160_i200
#CELL
  pure_quanta q_res *
  page160_i201
#CELL
  pure_quanta q_res *
  page160_i202
#CELL
  pure_quanta 74lvc2g17gw *
  page160_i26
#ISCELL
  logical_power universal_gnd *
  page160_i27
#ISCELL
  logical_power universal_gnd *
  page160_i28
#CELL
  pure_quanta q_cap *
  page160_i29
#ISCELL
  logical_power universal_power *
  page160_i30
#ISCELL
  standard offpage *
  page160_i67
#CELL
  pure_quanta q_res *
  page160_i95
